# T6G (Grand Teton) — schematic netlist excerpt (pin names and nets, part order shuffled) for the footprints in the layout excerpt that follows; sources: Cadence DE-HDL packaged netlist, KiCad conversion of 04192023_DAF0TMB3IC0_F0TG_MB_C_brd_V02_OCP.brd

PC512_2  Q_CAP  1UF 25V 10% X6S  pkg C0402  page 225 : A = SW_P12V_AUX_PVDD11_S3_P1_FLT ; B = GND
R49  Q_RES  33 5% CHIP  pkg 0402LF  page 80 : A = SCM_JTAG_MUX_R_S0 ; B = SCM_JTAG_MUX_S0

(kicad_pcb
	(version 20260206)
	(generator "pcbnew")
	(generator_version "10.0")
	(general
		(thickness 1.6)
		(legacy_teardrops no)
	)
	(paper "A4")
	(title_block
		(title "04192023_DAF0TMB3IC0_F0TG_MB_C_brd_V02_OCP.brd")
		(comment 1 "Grand Teton / footprints 2268-2269 of 8354")
	)
	(layers
		(0 "F.Cu" signal "TOP")
		(4 "In1.Cu" signal "GND")
		(6 "In2.Cu" signal "IN1")
		(8 "In3.Cu" signal "GND1")
		(10 "In4.Cu" signal "IN2")
		(12 "In5.Cu" signal "GND2")
		(14 "In6.Cu" signal "IN3")
		(16 "In7.Cu" signal "GND3")
		(18 "In8.Cu" signal "VCC")
		(20 "In9.Cu" signal "VCC1")
		(22 "In10.Cu" signal "GND4")
		(24 "In11.Cu" signal "IN4")
		(26 "In12.Cu" signal "GND5")
		(28 "In13.Cu" signal "IN5")
		(30 "In14.Cu" signal "GND6")
		(32 "In15.Cu" signal "IN6")
		(34 "In16.Cu" signal "GND7")
		(2 "B.Cu" signal "BOTTOM")
		(9 "F.Adhes" user "F.Adhesive")
		(11 "B.Adhes" user "B.Adhesive")
		(13 "F.Paste" user "Package Geometry/Pastemask Top")
		(15 "B.Paste" user "Package Geometry/Pastemask Bottom")
		(5 "F.SilkS" user "Ref Des/Silkscreen Top")
		(7 "B.SilkS" user "Ref Des/Silkscreen Bottom")
		(1 "F.Mask" user "Board Geometry/Soldermask Top")
		(3 "B.Mask" user "Board Geometry/Soldermask Bottom")
		(17 "Dwgs.User" user "User.Drawings")
		(19 "Cmts.User" user "User.Comments")
		(21 "Eco1.User" user "User.Eco1")
		(23 "Eco2.User" user "User.Eco2")
		(25 "Edge.Cuts" user "Board Geometry/Outline")
		(27 "Margin" user)
		(31 "F.CrtYd" user "Package Geometry/Place Bound Top")
		(29 "B.CrtYd" user "Package Geometry/Place Bound Bottom")
		(35 "F.Fab" user "Ref Des/Assembly Top")
		(33 "B.Fab" user "Ref Des/Assembly Bottom")
	)
	(footprint ""
		(layer "F.Cu")
		(at 167.132 -108.168948 180)
		(property "Reference" "R49"
			(at 0 0 180)
			(layer "F.SilkS")
			(hide yes)
			(effects
				(font
					(size 1.27 1.27)
				)
			)
		)
		(property "Value" ""
			(at 0 0 180)
			(layer "F.Fab")
			(effects
				(font
					(size 1.27 1.27)
				)
			)
		)
		(duplicate_pad_numbers_are_jumpers no)
		(fp_line
			(start 0.7874 0.4064)
			(end -0.7874 0.4064)
			(stroke
				(width 0.1524)
				(type default)
			)
			(layer "F.SilkS")
		)
		(fp_line
			(start 0.7874 -0.4064)
			(end 0.7874 0.4064)
			(stroke
				(width 0.1524)
				(type default)
			)
			(layer "F.SilkS")
		)
		(fp_line
			(start -0.7874 0.4064)
			(end -0.7874 -0.4064)
			(stroke
				(width 0.1524)
				(type default)
			)
			(layer "F.SilkS")
		)
		(fp_line
			(start -0.7874 -0.4064)
			(end 0.7874 -0.4064)
			(stroke
				(width 0.1524)
				(type default)
			)
			(layer "F.SilkS")
		)
		(fp_line
			(start 0.67945 0.3048)
			(end 0.120396 0.3048)
			(stroke
				(width 0.1)
				(type default)
			)
			(layer "F.Fab")
		)
		(fp_line
			(start 0.67945 -0.3048)
			(end 0.67945 0.3048)
			(stroke
				(width 0.1)
				(type default)
			)
			(layer "F.Fab")
		)
		(fp_line
			(start 0.12065 -0.2794)
			(end 0.12065 -0.3048)
			(stroke
				(width 0.1)
				(type default)
			)
			(layer "F.Fab")
		)
		(fp_line
			(start 0.12065 -0.3048)
			(end 0.67945 -0.3048)
			(stroke
				(width 0.1)
				(type default)
			)
			(layer "F.Fab")
		)
		(fp_line
			(start 0.120396 0.3048)
			(end 0.120396 0.2794)
			(stroke
				(width 0.1)
				(type default)
			)
			(layer "F.Fab")
		)
		(fp_line
			(start 0.120396 0.2794)
			(end -0.12065 0.2794)
			(stroke
				(width 0.1)
				(type default)
			)
			(layer "F.Fab")
		)
		(fp_line
			(start -0.12065 0.3048)
			(end -0.67945 0.3048)
			(stroke
				(width 0.1)
				(type default)
			)
			(layer "F.Fab")
		)
		(fp_line
			(start -0.12065 0.2794)
			(end -0.12065 0.3048)
			(stroke
				(width 0.1)
				(type default)
			)
			(layer "F.Fab")
		)
		(fp_line
			(start -0.12065 -0.2794)
			(end 0.12065 -0.2794)
			(stroke
				(width 0.1)
				(type default)
			)
			(layer "F.Fab")
		)
		(fp_line
			(start -0.12065 -0.305054)
			(end -0.12065 -0.2794)
			(stroke
				(width 0.1)
				(type default)
			)
			(layer "F.Fab")
		)
		(fp_line
			(start -0.67945 0.3048)
			(end -0.67945 -0.305054)
			(stroke
				(width 0.1)
				(type default)
			)
			(layer "F.Fab")
		)
		(fp_line
			(start -0.67945 -0.305054)
			(end -0.12065 -0.305054)
			(stroke
				(width 0.1)
				(type default)
			)
			(layer "F.Fab")
		)
		(pad "1" smd circle
			(at -0.40005 0 180)
			(size 0 0)
			(layers "F.Cu" "F.Mask" "F.Paste")
			(net "SCM_JTAG_MUX_R_S0")
		)
		(pad "2" smd circle
			(at 0.40005 0 180)
			(size 0 0)
			(layers "F.Cu" "F.Mask" "F.Paste")
			(net "SCM_JTAG_MUX_S0")
		)
	)
	(footprint ""
		(layer "F.Cu")
		(at 194.904106 -351.409254 -90)
		(property "Reference" "PC512_2"
			(at 0 0 270)
			(layer "F.SilkS")
			(hide yes)
			(effects
				(font
					(size 1.27 1.27)
				)
			)
		)
		(property "Value" ""
			(at 0 0 270)
			(layer "F.Fab")
			(effects
				(font
					(size 1.27 1.27)
				)
			)
		)
		(duplicate_pad_numbers_are_jumpers no)
		(fp_line
			(start -0.7874 0.4064)
			(end -0.7874 -0.4064)
			(stroke
				(width 0.1524)
				(type default)
			)
			(layer "F.SilkS")
		)
		(fp_line
			(start 0.7874 0.4064)
			(end -0.7874 0.4064)
			(stroke
				(width 0.1524)
				(type default)
			)
			(layer "F.SilkS")
		)
		(fp_line
			(start -0.7874 -0.4064)
			(end 0.7874 -0.4064)
			(stroke
				(width 0.1524)
				(type default)
			)
			(layer "F.SilkS")
		)
		(fp_line
			(start 0.7874 -0.4064)
			(end 0.7874 0.4064)
			(stroke
				(width 0.1524)
				(type default)
			)
			(layer "F.SilkS")
		)
		(fp_line
			(start -0.67945 0.3048)
			(end -0.67945 -0.305054)
			(stroke
				(width 0.1)
				(type default)
			)
			(layer "F.Fab")
		)
		(fp_line
			(start -0.12065 0.3048)
			(end -0.67945 0.3048)
			(stroke
				(width 0.1)
				(type default)
			)
			(layer "F.Fab")
		)
		(fp_line
			(start 0.120396 0.3048)
			(end 0.120396 0.2794)
			(stroke
				(width 0.1)
				(type default)
			)
			(layer "F.Fab")
		)
		(fp_line
			(start 0.67945 0.3048)
			(end 0.120396 0.3048)
			(stroke
				(width 0.1)
				(type default)
			)
			(layer "F.Fab")
		)
		(fp_line
			(start -0.12065 0.2794)
			(end -0.12065 0.3048)
			(stroke
				(width 0.1)
				(type default)
			)
			(layer "F.Fab")
		)
		(fp_line
			(start 0.120396 0.2794)
			(end -0.12065 0.2794)
			(stroke
				(width 0.1)
				(type default)
			)
			(layer "F.Fab")
		)
		(fp_line
			(start -0.12065 -0.2794)
			(end 0.12065 -0.2794)
			(stroke
				(width 0.1)
				(type default)
			)
			(layer "F.Fab")
		)
		(fp_line
			(start 0.12065 -0.2794)
			(end 0.12065 -0.3048)
			(stroke
				(width 0.1)
				(type default)
			)
			(layer "F.Fab")
		)
		(fp_line
			(start 0.12065 -0.3048)
			(end 0.67945 -0.3048)
			(stroke
				(width 0.1)
				(type default)
			)
			(layer "F.Fab")
		)
		(fp_line
			(start 0.67945 -0.3048)
			(end 0.67945 0.3048)
			(stroke
				(width 0.1)
				(type default)
			)
			(layer "F.Fab")
		)
		(fp_line
			(start -0.67945 -0.305054)
			(end -0.12065 -0.305054)
			(stroke
				(width 0.1)
				(type default)
			)
			(layer "F.Fab")
		)
		(fp_line
			(start -0.12065 -0.305054)
			(end -0.12065 -0.2794)
			(stroke
				(width 0.1)
				(type default)
			)
			(layer "F.Fab")
		)
		(pad "1" smd circle
			(at -0.40005 0 270)
			(size 0 0)
			(layers "F.Cu" "F.Mask" "F.Paste")
			(net "SW_P12V_AUX_PVDD11_S3_P1_FLT")
		)
		(pad "2" smd circle
			(at 0.40005 0 270)
			(size 0 0)
			(layers "F.Cu" "F.Mask" "F.Paste")
			(net "GND")
		)
	)
)
